(kicad_pcb
	(version 20260206)
	(generator "pcbnew")
	(generator_version "10.0")
	(general
		(thickness 1.6)
		(legacy_teardrops no)
	)
	(paper "A4")
	(title_block
		(title "panther-plus-userver — 13130-1b_20150205.brd")
		(comment 1 "Honey Badger (Wiwynn) / footprint 624 of 1509 (DIMM4), pads 79-85 of 210")
	)
	(layers
		(0 "F.Cu" signal "TOP")
		(4 "In1.Cu" signal "L2")
		(6 "In2.Cu" signal "L3")
		(8 "In3.Cu" signal "L4")
		(10 "In4.Cu" signal "L5")
		(12 "In5.Cu" signal "L6")
		(14 "In6.Cu" signal "L7")
		(16 "In7.Cu" signal "L8")
		(18 "In8.Cu" signal "L9")
		(20 "In9.Cu" signal "L10")
		(22 "In10.Cu" signal "L11")
		(2 "B.Cu" signal "BOTTOM")
		(9 "F.Adhes" user "F.Adhesive")
		(11 "B.Adhes" user "B.Adhesive")
		(13 "F.Paste" user "Package Geometry/Pastemask Top")
		(15 "B.Paste" user "Package Geometry/Pastemask Bottom")
		(5 "F.SilkS" user "Ref Des/Silkscreen Top")
		(7 "B.SilkS" user "Ref Des/Silkscreen Bottom")
		(1 "F.Mask" user "Board Geometry/Soldermask Top")
		(3 "B.Mask" user "Board Geometry/Soldermask Bottom")
		(17 "Dwgs.User" user "User.Drawings")
		(19 "Cmts.User" user "User.Comments")
		(21 "Eco1.User" user "User.Eco1")
		(23 "Eco2.User" user "User.Eco2")
		(25 "Edge.Cuts" user "Board Geometry/Outline")
		(27 "Margin" user)
		(31 "F.CrtYd" user "Package Geometry/Place Bound Top")
		(29 "B.CrtYd" user "Package Geometry/Place Bound Bottom")
		(35 "F.Fab" user "Ref Des/Assembly Top")
		(33 "B.Fab" user "Ref Des/Assembly Bottom")
	)
	(footprint ""
		(layer "F.Cu")
		(at 159.999934 -5.790692)
		(property "Reference" "DIMM4"
			(at 0 0 0)
			(layer "F.SilkS")
			(hide yes)
			(effects
				(font
					(size 1.27 1.27)
				)
			)
		)
		(property "Value" "DDR3-204P-174-COLAY-1-GP"
			(at -40.682164 -17.468088 0)
			(unlocked yes)
			(layer "F.Fab")
			(hide yes)
			(effects
				(font
					(size 1.016 1.016)
					(thickness 0.1524)
				)
			)
		)
		(property "Device Type" "AS0A626-H8SN-7H-COLAY-1"
			(at -40.682164 -18.992088 0)
			(unlocked yes)
			(layer "F.Fab")
			(hide yes)
			(effects
				(font
					(size 1.016 1.016)
					(thickness 0.1524)
				)
			)
		)
		(duplicate_pad_numbers_are_jumpers no)
		(pad "77" smd custom
			(at -6.450076 4.106672)
			(size 0.1143 0.1143)
			(layers "F.Cu" "F.Mask" "F.Paste")
			(net "M_B_DQS_DP8")
			(options
				(clearance outline)
				(anchor circle)
			)
			(primitives
				(gr_poly
					(pts
						(xy 0 0.9017) (xy -0.03175 0.89916) (xy -0.0635 0.889) (xy -0.09144 0.87376) (xy -0.11684 0.85344)
						(xy -0.13716 0.82804) (xy -0.1524 0.8001) (xy -0.16256 0.76835) (xy -0.1651 0.7366) (xy -0.1651 -0.13462)
						(xy -0.17272 -0.14224) (xy -0.19812 -0.1778) (xy -0.2032 -0.18796) (xy -0.20701 -0.19685) (xy -0.21209 -0.20701)
						(xy -0.2159 -0.21717) (xy -0.21844 -0.22733) (xy -0.22225 -0.23876) (xy -0.22352 -0.24892) (xy -0.22606 -0.25908)
						(xy -0.22733 -0.27051) (xy -0.22733 -0.28067) (xy -0.2286 -0.2921) (xy -0.22733 -0.30353) (xy -0.22733 -0.31369)
						(xy -0.22606 -0.32512) (xy -0.22352 -0.33528) (xy -0.22225 -0.34544) (xy -0.21844 -0.35687) (xy -0.2159 -0.36703)
						(xy -0.21209 -0.37719) (xy -0.20701 -0.38735) (xy -0.2032 -0.39624) (xy -0.19812 -0.4064) (xy -0.17272 -0.44196)
						(xy -0.1651 -0.44958) (xy -0.1651 -0.7366) (xy -0.16256 -0.76835) (xy -0.1524 -0.8001) (xy -0.13716 -0.82804)
						(xy -0.11684 -0.85344) (xy -0.09144 -0.87376) (xy -0.0635 -0.889) (xy -0.03175 -0.89916) (xy 0 -0.9017)
						(xy 0.03175 -0.89916) (xy 0.0635 -0.889) (xy 0.09144 -0.87376) (xy 0.11684 -0.85344) (xy 0.13716 -0.82804)
						(xy 0.1524 -0.8001) (xy 0.16256 -0.76835) (xy 0.1651 -0.7366) (xy 0.1651 -0.44958) (xy 0.17272 -0.44196)
						(xy 0.19812 -0.4064) (xy 0.2032 -0.39624) (xy 0.20701 -0.38735) (xy 0.21209 -0.37719) (xy 0.2159 -0.36703)
						(xy 0.21844 -0.35687) (xy 0.22225 -0.34544) (xy 0.22352 -0.33528) (xy 0.22606 -0.32512) (xy 0.22733 -0.31369)
						(xy 0.22733 -0.30353) (xy 0.2286 -0.2921) (xy 0.22733 -0.28067) (xy 0.22733 -0.27051) (xy 0.22606 -0.25908)
						(xy 0.22352 -0.24892) (xy 0.22225 -0.23876) (xy 0.21844 -0.22733) (xy 0.2159 -0.21717) (xy 0.21209 -0.20701)
						(xy 0.20701 -0.19685) (xy 0.2032 -0.18796) (xy 0.19812 -0.1778) (xy 0.17272 -0.14224) (xy 0.1651 -0.13462)
						(xy 0.1651 0.7366) (xy 0.16256 0.76835) (xy 0.1524 0.8001) (xy 0.13716 0.82804) (xy 0.11684 0.85344)
						(xy 0.09144 0.87376) (xy 0.0635 0.889) (xy 0.03175 0.89916)
					)
					(width 0)
					(fill yes)
				)
			)
		)
		(pad "78" smd custom
			(at -6.150102 -4.106672)
			(size 0.1143 0.1143)
			(layers "F.Cu" "F.Mask" "F.Paste")
			(net "GND")
			(options
				(clearance outline)
				(anchor circle)
			)
			(primitives
				(gr_poly
					(pts
						(xy 0 0.9017) (xy -0.03175 0.89916) (xy -0.0635 0.889) (xy -0.09144 0.87376) (xy -0.11684 0.85344)
						(xy -0.13716 0.82804) (xy -0.1524 0.8001) (xy -0.16256 0.76835) (xy -0.1651 0.7366) (xy -0.1651 0.44958)
						(xy -0.17272 0.44196) (xy -0.19812 0.4064) (xy -0.2032 0.39624) (xy -0.20701 0.38735) (xy -0.21209 0.37719)
						(xy -0.2159 0.36703) (xy -0.21844 0.35687) (xy -0.22225 0.34544) (xy -0.22352 0.33528) (xy -0.22606 0.32512)
						(xy -0.22733 0.31369) (xy -0.22733 0.30353) (xy -0.2286 0.2921) (xy -0.22733 0.28067) (xy -0.22733 0.27051)
						(xy -0.22606 0.25908) (xy -0.22352 0.24892) (xy -0.22225 0.23876) (xy -0.21844 0.22733) (xy -0.2159 0.21717)
						(xy -0.21209 0.20701) (xy -0.20701 0.19685) (xy -0.2032 0.18796) (xy -0.19812 0.1778) (xy -0.17272 0.14224)
						(xy -0.1651 0.13462) (xy -0.1651 -0.7366) (xy -0.16256 -0.76835) (xy -0.1524 -0.8001) (xy -0.13716 -0.82804)
						(xy -0.11684 -0.85344) (xy -0.09144 -0.87376) (xy -0.0635 -0.889) (xy -0.03175 -0.89916) (xy 0 -0.9017)
						(xy 0.03175 -0.89916) (xy 0.0635 -0.889) (xy 0.09144 -0.87376) (xy 0.11684 -0.85344) (xy 0.13716 -0.82804)
						(xy 0.1524 -0.8001) (xy 0.16256 -0.76835) (xy 0.1651 -0.7366) (xy 0.1651 0.13462) (xy 0.17272 0.14224)
						(xy 0.19812 0.1778) (xy 0.2032 0.18796) (xy 0.20701 0.19685) (xy 0.21209 0.20701) (xy 0.2159 0.21717)
						(xy 0.21844 0.22733) (xy 0.22225 0.23876) (xy 0.22352 0.24892) (xy 0.22606 0.25908) (xy 0.22733 0.27051)
						(xy 0.22733 0.28067) (xy 0.2286 0.2921) (xy 0.22733 0.30353) (xy 0.22733 0.31369) (xy 0.22606 0.32512)
						(xy 0.22352 0.33528) (xy 0.22225 0.34544) (xy 0.21844 0.35687) (xy 0.2159 0.36703) (xy 0.21209 0.37719)
						(xy 0.20701 0.38735) (xy 0.2032 0.39624) (xy 0.19812 0.4064) (xy 0.17272 0.44196) (xy 0.1651 0.44958)
						(xy 0.1651 0.7366) (xy 0.16256 0.76835) (xy 0.1524 0.8001) (xy 0.13716 0.82804) (xy 0.11684 0.85344)
						(xy 0.09144 0.87376) (xy 0.0635 0.889) (xy 0.03175 0.89916)
					)
					(width 0)
					(fill yes)
				)
			)
		)
		(pad "79" smd custom
			(at -5.849874 4.106672)
			(size 0.1143 0.1143)
			(layers "F.Cu" "F.Mask" "F.Paste")
			(net "GND")
			(options
				(clearance outline)
				(anchor circle)
			)
			(primitives
				(gr_poly
					(pts
						(xy 0 0.9017) (xy -0.03175 0.89916) (xy -0.0635 0.889) (xy -0.09144 0.87376) (xy -0.11684 0.85344)
						(xy -0.13716 0.82804) (xy -0.1524 0.8001) (xy -0.16256 0.76835) (xy -0.1651 0.7366) (xy -0.1651 0.11938)
						(xy -0.17272 0.11176) (xy -0.19812 0.0762) (xy -0.2032 0.06604) (xy -0.20701 0.05715) (xy -0.21209 0.04699)
						(xy -0.2159 0.03683) (xy -0.21844 0.02667) (xy -0.22225 0.01524) (xy -0.22352 0.00508) (xy -0.22606 -0.00508)
						(xy -0.22733 -0.01651) (xy -0.22733 -0.02667) (xy -0.2286 -0.0381) (xy -0.22733 -0.04953) (xy -0.22733 -0.05969)
						(xy -0.22606 -0.07112) (xy -0.22352 -0.08128) (xy -0.22225 -0.09144) (xy -0.21844 -0.10287) (xy -0.2159 -0.11303)
						(xy -0.21209 -0.12319) (xy -0.20701 -0.13335) (xy -0.2032 -0.14224) (xy -0.19812 -0.1524) (xy -0.17272 -0.18796)
						(xy -0.1651 -0.19558) (xy -0.1651 -0.7366) (xy -0.16256 -0.76835) (xy -0.1524 -0.8001) (xy -0.13716 -0.82804)
						(xy -0.11684 -0.85344) (xy -0.09144 -0.87376) (xy -0.0635 -0.889) (xy -0.03175 -0.89916) (xy 0 -0.9017)
						(xy 0.03175 -0.89916) (xy 0.0635 -0.889) (xy 0.09144 -0.87376) (xy 0.11684 -0.85344) (xy 0.13716 -0.82804)
						(xy 0.1524 -0.8001) (xy 0.16256 -0.76835) (xy 0.1651 -0.7366) (xy 0.1651 -0.19685) (xy 0.17272 -0.18923)
						(xy 0.17907 -0.18034) (xy 0.18669 -0.17145) (xy 0.19177 -0.16256) (xy 0.19812 -0.15367) (xy 0.20828 -0.13335)
						(xy 0.21971 -0.10287) (xy 0.22225 -0.09271) (xy 0.22479 -0.08128) (xy 0.22606 -0.07112) (xy 0.2286 -0.05969)
						(xy 0.2286 -0.01651) (xy 0.22606 -0.00508) (xy 0.22479 0.00508) (xy 0.22225 0.01651) (xy 0.21971 0.02667)
						(xy 0.20828 0.05715) (xy 0.19812 0.07747) (xy 0.19177 0.08636) (xy 0.18669 0.09525) (xy 0.17907 0.10414)
						(xy 0.17272 0.11303) (xy 0.1651 0.12065) (xy 0.1651 0.7366) (xy 0.16256 0.76835) (xy 0.1524 0.8001)
						(xy 0.13716 0.82804) (xy 0.11684 0.85344) (xy 0.09144 0.87376) (xy 0.0635 0.889) (xy 0.03175 0.89916)
					)
					(width 0)
					(fill yes)
				)
			)
		)
		(pad "80" smd custom
			(at -5.5499 -4.106672)
			(size 0.1143 0.1143)
			(layers "F.Cu" "F.Mask" "F.Paste")
			(net "M_B_ECC2")
			(options
				(clearance outline)
				(anchor circle)
			)
			(primitives
				(gr_poly
					(pts
						(xy 0 0.9017) (xy -0.03175 0.89916) (xy -0.0635 0.889) (xy -0.09144 0.87376) (xy -0.11684 0.85344)
						(xy -0.13716 0.82804) (xy -0.1524 0.8001) (xy -0.16256 0.76835) (xy -0.1651 0.7366) (xy -0.1651 0.19685)
						(xy -0.17272 0.18923) (xy -0.17907 0.18034) (xy -0.18669 0.17145) (xy -0.19177 0.16256) (xy -0.19812 0.15367)
						(xy -0.20828 0.13335) (xy -0.21971 0.10287) (xy -0.22225 0.09271) (xy -0.22479 0.08128) (xy -0.22606 0.07112)
						(xy -0.2286 0.05969) (xy -0.2286 0.01651) (xy -0.22606 0.00508) (xy -0.22479 -0.00508) (xy -0.22225 -0.01651)
						(xy -0.21971 -0.02667) (xy -0.20828 -0.05715) (xy -0.19812 -0.07747) (xy -0.19177 -0.08636) (xy -0.18669 -0.09525)
						(xy -0.17907 -0.10414) (xy -0.17272 -0.11303) (xy -0.1651 -0.12065) (xy -0.1651 -0.7366) (xy -0.16256 -0.76835)
						(xy -0.1524 -0.8001) (xy -0.13716 -0.82804) (xy -0.11684 -0.85344) (xy -0.09144 -0.87376) (xy -0.0635 -0.889)
						(xy -0.03175 -0.89916) (xy 0 -0.9017) (xy 0.03175 -0.89916) (xy 0.0635 -0.889) (xy 0.09144 -0.87376)
						(xy 0.11684 -0.85344) (xy 0.13716 -0.82804) (xy 0.1524 -0.8001) (xy 0.16256 -0.76835) (xy 0.1651 -0.7366)
						(xy 0.1651 -0.11938) (xy 0.17272 -0.11176) (xy 0.19812 -0.0762) (xy 0.2032 -0.06604) (xy 0.20701 -0.05715)
						(xy 0.21209 -0.04699) (xy 0.2159 -0.03683) (xy 0.21844 -0.02667) (xy 0.22225 -0.01524) (xy 0.22352 -0.00508)
						(xy 0.22606 0.00508) (xy 0.22733 0.01651) (xy 0.22733 0.02667) (xy 0.2286 0.0381) (xy 0.22733 0.04953)
						(xy 0.22733 0.05969) (xy 0.22606 0.07112) (xy 0.22352 0.08128) (xy 0.22225 0.09144) (xy 0.21844 0.10287)
						(xy 0.2159 0.11303) (xy 0.21209 0.12319) (xy 0.20701 0.13335) (xy 0.2032 0.14224) (xy 0.19812 0.1524)
						(xy 0.17272 0.18796) (xy 0.1651 0.19558) (xy 0.1651 0.7366) (xy 0.16256 0.76835) (xy 0.1524 0.8001)
						(xy 0.13716 0.82804) (xy 0.11684 0.85344) (xy 0.09144 0.87376) (xy 0.0635 0.889) (xy 0.03175 0.89916)
					)
					(width 0)
					(fill yes)
				)
			)
		)
		(pad "81" smd custom
			(at -5.249926 4.106672)
			(size 0.1143 0.1143)
			(layers "F.Cu" "F.Mask" "F.Paste")
			(net "M_B_ECC6")
			(options
				(clearance outline)
				(anchor circle)
			)
			(primitives
				(gr_poly
					(pts
						(xy 0 0.9017) (xy -0.03175 0.89916) (xy -0.0635 0.889) (xy -0.09144 0.87376) (xy -0.11684 0.85344)
						(xy -0.13716 0.82804) (xy -0.1524 0.8001) (xy -0.16256 0.76835) (xy -0.1651 0.7366) (xy -0.1651 -0.13462)
						(xy -0.17272 -0.14224) (xy -0.19812 -0.1778) (xy -0.2032 -0.18796) (xy -0.20701 -0.19685) (xy -0.21209 -0.20701)
						(xy -0.2159 -0.21717) (xy -0.21844 -0.22733) (xy -0.22225 -0.23876) (xy -0.22352 -0.24892) (xy -0.22606 -0.25908)
						(xy -0.22733 -0.27051) (xy -0.22733 -0.28067) (xy -0.2286 -0.2921) (xy -0.22733 -0.30353) (xy -0.22733 -0.31369)
						(xy -0.22606 -0.32512) (xy -0.22352 -0.33528) (xy -0.22225 -0.34544) (xy -0.21844 -0.35687) (xy -0.2159 -0.36703)
						(xy -0.21209 -0.37719) (xy -0.20701 -0.38735) (xy -0.2032 -0.39624) (xy -0.19812 -0.4064) (xy -0.17272 -0.44196)
						(xy -0.1651 -0.44958) (xy -0.1651 -0.7366) (xy -0.16256 -0.76835) (xy -0.1524 -0.8001) (xy -0.13716 -0.82804)
						(xy -0.11684 -0.85344) (xy -0.09144 -0.87376) (xy -0.0635 -0.889) (xy -0.03175 -0.89916) (xy 0 -0.9017)
						(xy 0.03175 -0.89916) (xy 0.0635 -0.889) (xy 0.09144 -0.87376) (xy 0.11684 -0.85344) (xy 0.13716 -0.82804)
						(xy 0.1524 -0.8001) (xy 0.16256 -0.76835) (xy 0.1651 -0.7366) (xy 0.1651 -0.44958) (xy 0.17272 -0.44196)
						(xy 0.19812 -0.4064) (xy 0.2032 -0.39624) (xy 0.20701 -0.38735) (xy 0.21209 -0.37719) (xy 0.2159 -0.36703)
						(xy 0.21844 -0.35687) (xy 0.22225 -0.34544) (xy 0.22352 -0.33528) (xy 0.22606 -0.32512) (xy 0.22733 -0.31369)
						(xy 0.22733 -0.30353) (xy 0.2286 -0.2921) (xy 0.22733 -0.28067) (xy 0.22733 -0.27051) (xy 0.22606 -0.25908)
						(xy 0.22352 -0.24892) (xy 0.22225 -0.23876) (xy 0.21844 -0.22733) (xy 0.2159 -0.21717) (xy 0.21209 -0.20701)
						(xy 0.20701 -0.19685) (xy 0.2032 -0.18796) (xy 0.19812 -0.1778) (xy 0.17272 -0.14224) (xy 0.1651 -0.13462)
						(xy 0.1651 0.7366) (xy 0.16256 0.76835) (xy 0.1524 0.8001) (xy 0.13716 0.82804) (xy 0.11684 0.85344)
						(xy 0.09144 0.87376) (xy 0.0635 0.889) (xy 0.03175 0.89916)
					)
					(width 0)
					(fill yes)
				)
			)
		)
		(pad "82" smd custom
			(at -4.949952 -4.106672)
			(size 0.1143 0.1143)
			(layers "F.Cu" "F.Mask" "F.Paste")
			(net "M_B_ECC3")
			(options
				(clearance outline)
				(anchor circle)
			)
			(primitives
				(gr_poly
					(pts
						(xy 0 0.9017) (xy -0.03175 0.89916) (xy -0.0635 0.889) (xy -0.09144 0.87376) (xy -0.11684 0.85344)
						(xy -0.13716 0.82804) (xy -0.1524 0.8001) (xy -0.16256 0.76835) (xy -0.1651 0.7366) (xy -0.1651 0.44958)
						(xy -0.17272 0.44196) (xy -0.19812 0.4064) (xy -0.2032 0.39624) (xy -0.20701 0.38735) (xy -0.21209 0.37719)
						(xy -0.2159 0.36703) (xy -0.21844 0.35687) (xy -0.22225 0.34544) (xy -0.22352 0.33528) (xy -0.22606 0.32512)
						(xy -0.22733 0.31369) (xy -0.22733 0.30353) (xy -0.2286 0.2921) (xy -0.22733 0.28067) (xy -0.22733 0.27051)
						(xy -0.22606 0.25908) (xy -0.22352 0.24892) (xy -0.22225 0.23876) (xy -0.21844 0.22733) (xy -0.2159 0.21717)
						(xy -0.21209 0.20701) (xy -0.20701 0.19685) (xy -0.2032 0.18796) (xy -0.19812 0.1778) (xy -0.17272 0.14224)
						(xy -0.1651 0.13462) (xy -0.1651 -0.7366) (xy -0.16256 -0.76835) (xy -0.1524 -0.8001) (xy -0.13716 -0.82804)
						(xy -0.11684 -0.85344) (xy -0.09144 -0.87376) (xy -0.0635 -0.889) (xy -0.03175 -0.89916) (xy 0 -0.9017)
						(xy 0.03175 -0.89916) (xy 0.0635 -0.889) (xy 0.09144 -0.87376) (xy 0.11684 -0.85344) (xy 0.13716 -0.82804)
						(xy 0.1524 -0.8001) (xy 0.16256 -0.76835) (xy 0.1651 -0.7366) (xy 0.1651 0.13462) (xy 0.17272 0.14224)
						(xy 0.19812 0.1778) (xy 0.2032 0.18796) (xy 0.20701 0.19685) (xy 0.21209 0.20701) (xy 0.2159 0.21717)
						(xy 0.21844 0.22733) (xy 0.22225 0.23876) (xy 0.22352 0.24892) (xy 0.22606 0.25908) (xy 0.22733 0.27051)
						(xy 0.22733 0.28067) (xy 0.2286 0.2921) (xy 0.22733 0.30353) (xy 0.22733 0.31369) (xy 0.22606 0.32512)
						(xy 0.22352 0.33528) (xy 0.22225 0.34544) (xy 0.21844 0.35687) (xy 0.2159 0.36703) (xy 0.21209 0.37719)
						(xy 0.20701 0.38735) (xy 0.2032 0.39624) (xy 0.19812 0.4064) (xy 0.17272 0.44196) (xy 0.1651 0.44958)
						(xy 0.1651 0.7366) (xy 0.16256 0.76835) (xy 0.1524 0.8001) (xy 0.13716 0.82804) (xy 0.11684 0.85344)
						(xy 0.09144 0.87376) (xy 0.0635 0.889) (xy 0.03175 0.89916)
					)
					(width 0)
					(fill yes)
				)
			)
		)
		(pad "83" smd custom
			(at -4.649978 4.106672)
			(size 0.1143 0.1143)
			(layers "F.Cu" "F.Mask" "F.Paste")
			(net "M_B_ECC7")
			(options
				(clearance outline)
				(anchor circle)
			)
			(primitives
				(gr_poly
					(pts
						(xy 0 0.9017) (xy -0.03175 0.89916) (xy -0.0635 0.889) (xy -0.09144 0.87376) (xy -0.11684 0.85344)
						(xy -0.13716 0.82804) (xy -0.1524 0.8001) (xy -0.16256 0.76835) (xy -0.1651 0.7366) (xy -0.1651 0.11938)
						(xy -0.17272 0.11176) (xy -0.19812 0.0762) (xy -0.2032 0.06604) (xy -0.20701 0.05715) (xy -0.21209 0.04699)
						(xy -0.2159 0.03683) (xy -0.21844 0.02667) (xy -0.22225 0.01524) (xy -0.22352 0.00508) (xy -0.22606 -0.00508)
						(xy -0.22733 -0.01651) (xy -0.22733 -0.02667) (xy -0.2286 -0.0381) (xy -0.22733 -0.04953) (xy -0.22733 -0.05969)
						(xy -0.22606 -0.07112) (xy -0.22352 -0.08128) (xy -0.22225 -0.09144) (xy -0.21844 -0.10287) (xy -0.2159 -0.11303)
						(xy -0.21209 -0.12319) (xy -0.20701 -0.13335) (xy -0.2032 -0.14224) (xy -0.19812 -0.1524) (xy -0.17272 -0.18796)
						(xy -0.1651 -0.19558) (xy -0.1651 -0.7366) (xy -0.16256 -0.76835) (xy -0.1524 -0.8001) (xy -0.13716 -0.82804)
						(xy -0.11684 -0.85344) (xy -0.09144 -0.87376) (xy -0.0635 -0.889) (xy -0.03175 -0.89916) (xy 0 -0.9017)
						(xy 0.03175 -0.89916) (xy 0.0635 -0.889) (xy 0.09144 -0.87376) (xy 0.11684 -0.85344) (xy 0.13716 -0.82804)
						(xy 0.1524 -0.8001) (xy 0.16256 -0.76835) (xy 0.1651 -0.7366) (xy 0.1651 -0.19685) (xy 0.17272 -0.18923)
						(xy 0.17907 -0.18034) (xy 0.18669 -0.17145) (xy 0.19177 -0.16256) (xy 0.19812 -0.15367) (xy 0.20828 -0.13335)
						(xy 0.21971 -0.10287) (xy 0.22225 -0.09271) (xy 0.22479 -0.08128) (xy 0.22606 -0.07112) (xy 0.2286 -0.05969)
						(xy 0.2286 -0.01651) (xy 0.22606 -0.00508) (xy 0.22479 0.00508) (xy 0.22225 0.01651) (xy 0.21971 0.02667)
						(xy 0.20828 0.05715) (xy 0.19812 0.07747) (xy 0.19177 0.08636) (xy 0.18669 0.09525) (xy 0.17907 0.10414)
						(xy 0.17272 0.11303) (xy 0.1651 0.12065) (xy 0.1651 0.7366) (xy 0.16256 0.76835) (xy 0.1524 0.8001)
						(xy 0.13716 0.82804) (xy 0.11684 0.85344) (xy 0.09144 0.87376) (xy 0.0635 0.889) (xy 0.03175 0.89916)
					)
					(width 0)
					(fill yes)
				)
			)
		)
	)
)
